# BASEBOARD_FAB2 (Tioga Pass) — schematic parts with pin connectivity, parts 4744–4751 of 4751; source: Cadence DE-HDL packaged netlist (pstxprt.dat, pstxnet.dat, pstchip.dat)

Y3F1  OSC_C  156.25MHZ OSC  pkg 6P10  page 104
  1  ENABLE_DISABLE  BI  = FM_CPU1_STL_BRD_OSC_EN
  2  NC_GND  NC  = NC_CLK_156M_CPU1_OSC
  3  GND  GROUND  = GND
  4  \out\  OUT  = CLK_156M_OSC_BRD_CPU1_DP
  5  OUT_N  OUT  = CLK_156M_OSC_BRD_CPU1_DN
  6  VCC  POWER  = P3V3

Y6F1  OSC_C  156.25MHZ OSC  pkg 6P10  page 104
  1  ENABLE_DISABLE  BI  = FM_CPU0_STL_BRD_OSC_EN
  2  NC_GND  NC  = NC_CLK_156M_CPU0_OSC
  3  GND  GROUND  = GND
  4  \out\  OUT  = CLK_156M_OSC_BRD_CPU0_DP
  5  OUT_N  OUT  = CLK_156M_OSC_BRD_CPU0_DN
  6  VCC  POWER  = P3V3

Y7C1  CRYSTAL  48.000MHZ IC  pkg 2013  page 114 : 1 = XTAL_PCH_48M_IN ; 3 = XTAL_PCH_48M_OUT
Y7C2  CRYSTAL  32.768KHZ IC  pkg SM  page 114 : 1 = XTAL_33K_RTC1 ; 2 = XTAL_33K_RTC2
Y8C1  CRYSTAL  25.000MHZ IC  pkg 2013  page 118 : 1 = XTAL_KR_25M_IN ; 3 = XTAL_KR_25M_OUT
Y8F1  CRYSTAL  25.000MHZ IC  pkg 2013LF  page 101 : 1 = XTAL_CK_MNG_IN ; 3 = XTAL_CK_MNG_OUT
Y9E1  CRYSTAL  25.000MHZ IC  pkg 2013  page 139 : 1 = XTAL_25MHZ_IN ; 3 = XTAL_25MHZ_OUT_R

Y9F2  OSC_C  24MHZ OSC  pkg SM4  page 145
  1  ENABLE_CONTROL  IN  = PU_24M_OSC_OE
  2  GND  GROUND  = GND
  3  \out\  OUT  = CLK_24M_BMC_CLKIN_R
  4  VDD  POWER  = P3V3_STBY
